# BASEBOARD_FAB2 (Tioga Pass) — schematic netlist excerpt (pin names and nets, part order shuffled) for the footprints in the layout excerpt that follows; sources: Cadence DE-HDL packaged netlist, KiCad conversion of Wiwynn_Tioga_Pass_MB.brd

C7G22  CAP  0.22UF 16V 10% X7R  pkg 0402  page 105 : A = P3E_CPU0_PE2_SS_TXN<7> ; B = P3E_CPU0_PE2_SS_C_TXN<7>
C1G10  CAP_A  0.01UF 25V 10% X7R  pkg 0402V  page 80 : A = M_H_VREF ; B = GND
C7F8  CAP  1000PF 50V 10% EMPTY  pkg 0402LF  page 231 : A = FM_PVPP_CPU0_EN ; B = AGND_PVPP_ABC

(kicad_pcb
	(version 20260206)
	(generator "pcbnew")
	(generator_version "10.0")
	(general
		(thickness 1.6)
		(legacy_teardrops no)
	)
	(paper "A4")
	(title_block
		(title "Wiwynn_Tioga_Pass_MB.brd")
		(comment 1 "Tioga Pass / footprints 936-938 of 4770")
	)
	(layers
		(0 "F.Cu" signal "TOP")
		(4 "In1.Cu" signal "L2GND")
		(6 "In2.Cu" signal "L3")
		(8 "In3.Cu" signal "L4GND")
		(10 "In4.Cu" signal "L5")
		(12 "In5.Cu" signal "L6GND")
		(14 "In6.Cu" signal "L7VCC")
		(16 "In7.Cu" signal "L8VCC")
		(18 "In8.Cu" signal "L9GND")
		(20 "In9.Cu" signal "L10")
		(22 "In10.Cu" signal "L11GND")
		(24 "In11.Cu" signal "L12")
		(26 "In12.Cu" signal "L13GND")
		(2 "B.Cu" signal "BOTTOM")
		(9 "F.Adhes" user "F.Adhesive")
		(11 "B.Adhes" user "B.Adhesive")
		(13 "F.Paste" user "Package Geometry/Pastemask Top")
		(15 "B.Paste" user "Package Geometry/Pastemask Bottom")
		(5 "F.SilkS" user "Ref Des/Silkscreen Top")
		(7 "B.SilkS" user "Ref Des/Silkscreen Bottom")
		(1 "F.Mask" user "Board Geometry/Soldermask Top")
		(3 "B.Mask" user "Board Geometry/Soldermask Bottom")
		(17 "Dwgs.User" user "User.Drawings")
		(19 "Cmts.User" user "User.Comments")
		(21 "Eco1.User" user "User.Eco1")
		(23 "Eco2.User" user "User.Eco2")
		(25 "Edge.Cuts" user "Board Geometry/Outline")
		(27 "Margin" user)
		(31 "F.CrtYd" user "Package Geometry/Place Bound Top")
		(29 "B.CrtYd" user "Package Geometry/Place Bound Bottom")
		(35 "F.Fab" user "Ref Des/Assembly Top")
		(33 "B.Fab" user "Ref Des/Assembly Bottom")
	)
	(footprint ""
		(layer "F.Cu")
		(at 30.579568 -12.923012 90)
		(property "Reference" "C1G10"
			(at 0 0 90)
			(layer "F.SilkS")
			(hide yes)
			(effects
				(font
					(size 1.27 1.27)
				)
			)
		)
		(property "Value" ""
			(at 0 0 90)
			(layer "F.Fab")
			(effects
				(font
					(size 1.27 1.27)
				)
			)
		)
		(duplicate_pad_numbers_are_jumpers no)
		(fp_poly
			(pts
				(xy 0.3048 -0.1016) (xy 0.3048 0.9906) (xy -0.3048 0.9906) (xy -0.3048 -0.1016)
			)
			(stroke
				(width 0)
				(type default)
			)
			(fill no)
			(layer "F.CrtYd")
		)
		(fp_line
			(start 0.3048 -0.1016)
			(end -0.3048 -0.1016)
			(stroke
				(width 0.1)
				(type default)
			)
			(layer "F.Fab")
		)
		(fp_line
			(start -0.3048 -0.1016)
			(end -0.3048 0.9906)
			(stroke
				(width 0.1)
				(type default)
			)
			(layer "F.Fab")
		)
		(fp_line
			(start 0.3048 0.9906)
			(end 0.3048 -0.1016)
			(stroke
				(width 0.1)
				(type default)
			)
			(layer "F.Fab")
		)
		(fp_line
			(start -0.3048 0.9906)
			(end 0.3048 0.9906)
			(stroke
				(width 0.1)
				(type default)
			)
			(layer "F.Fab")
		)
		(pad "1" smd rect
			(at 0 0 90)
			(size 0.508 0.508)
			(layers "F.Cu" "F.Mask" "F.Paste")
			(net "M_H_VREF")
		)
		(pad "2" smd rect
			(at 0 0.889 90)
			(size 0.508 0.508)
			(layers "F.Cu" "F.Mask" "F.Paste")
			(net "GND")
		)
		(zone
			(layer "F.Cu")
			(hatch none 0.5)
			(connect_pads
				(clearance 0)
			)
			(min_thickness 0.25)
			(keepout
				(tracks allowed)
				(vias not_allowed)
				(pads allowed)
				(copperpour not_allowed)
				(footprints allowed)
			)
			(placement
				(enabled no)
				(sheetname "")
			)
			(fill
				(thermal_gap 0.5)
				(thermal_bridge_width 0.5)
				(island_removal_mode 0)
			)
			(polygon
				(pts
					(xy 30.833568 -12.669012) (xy 30.833568 -13.177012) (xy 31.214568 -13.177012) (xy 31.214568 -12.669012)
				)
			)
		)
		(zone
			(layer "F.Cu")
			(hatch none 0.5)
			(connect_pads
				(clearance 0)
			)
			(min_thickness 0.25)
			(keepout
				(tracks not_allowed)
				(vias allowed)
				(pads allowed)
				(copperpour not_allowed)
				(footprints allowed)
			)
			(placement
				(enabled no)
				(sheetname "")
			)
			(fill
				(thermal_gap 0.5)
				(thermal_bridge_width 0.5)
				(island_removal_mode 0)
			)
			(polygon
				(pts
					(xy 31.214568 -12.669012) (xy 31.214568 -13.177012) (xy 30.833568 -13.177012) (xy 30.833568 -12.669012)
				)
			)
		)
	)
	(footprint ""
		(layer "F.Cu")
		(at 341.249 -23.749)
		(property "Reference" "C7F8"
			(at 0 0 0)
			(layer "F.SilkS")
			(hide yes)
			(effects
				(font
					(size 1.27 1.27)
				)
			)
		)
		(property "Value" ""
			(at 0 0 0)
			(layer "F.Fab")
			(effects
				(font
					(size 1.27 1.27)
				)
			)
		)
		(duplicate_pad_numbers_are_jumpers no)
		(fp_rect
			(start 0.3048 0.9906)
			(end -0.3048 -0.1016)
			(stroke
				(width 0)
				(type default)
			)
			(fill no)
			(layer "F.CrtYd")
		)
		(fp_line
			(start -0.3048 -0.1016)
			(end -0.3048 0.9906)
			(stroke
				(width 0.1)
				(type default)
			)
			(layer "F.Fab")
		)
		(fp_line
			(start -0.3048 0.9906)
			(end 0.3048 0.9906)
			(stroke
				(width 0.1)
				(type default)
			)
			(layer "F.Fab")
		)
		(fp_line
			(start 0.3048 -0.1016)
			(end -0.3048 -0.1016)
			(stroke
				(width 0.1)
				(type default)
			)
			(layer "F.Fab")
		)
		(fp_line
			(start 0.3048 0.9906)
			(end 0.3048 -0.1016)
			(stroke
				(width 0.1)
				(type default)
			)
			(layer "F.Fab")
		)
		(pad "1" smd rect
			(at 0 0)
			(size 0.508 0.508)
			(layers "F.Cu" "F.Mask" "F.Paste")
			(net "FM_PVPP_CPU0_EN")
		)
		(pad "2" smd rect
			(at 0 0.889)
			(size 0.508 0.508)
			(layers "F.Cu" "F.Mask" "F.Paste")
			(net "AGND_PVPP_ABC")
		)
		(zone
			(layer "F.Cu")
			(hatch none 0.5)
			(connect_pads
				(clearance 0)
			)
			(min_thickness 0.25)
			(keepout
				(tracks allowed)
				(vias not_allowed)
				(pads allowed)
				(copperpour not_allowed)
				(footprints allowed)
			)
			(placement
				(enabled no)
				(sheetname "")
			)
			(fill
				(thermal_gap 0.5)
				(thermal_bridge_width 0.5)
				(island_removal_mode 0)
			)
			(polygon
				(pts
					(xy 341.503 -23.114) (xy 341.503 -23.495) (xy 340.995 -23.495) (xy 340.995 -23.114)
				)
			)
		)
		(zone
			(layer "F.Cu")
			(hatch none 0.5)
			(connect_pads
				(clearance 0)
			)
			(min_thickness 0.25)
			(keepout
				(tracks not_allowed)
				(vias allowed)
				(pads allowed)
				(copperpour not_allowed)
				(footprints allowed)
			)
			(placement
				(enabled no)
				(sheetname "")
			)
			(fill
				(thermal_gap 0.5)
				(thermal_bridge_width 0.5)
				(island_removal_mode 0)
			)
			(polygon
				(pts
					(xy 341.503 -23.114) (xy 341.503 -23.495) (xy 340.995 -23.495) (xy 340.995 -23.114)
				)
			)
		)
	)
	(footprint ""
		(layer "F.Cu")
		(at 394.143992 -10.917936)
		(property "Reference" "C7G22"
			(at 0 0 0)
			(layer "F.SilkS")
			(hide yes)
			(effects
				(font
					(size 1.27 1.27)
				)
			)
		)
		(property "Value" ""
			(at 0 0 0)
			(layer "F.Fab")
			(effects
				(font
					(size 1.27 1.27)
				)
			)
		)
		(duplicate_pad_numbers_are_jumpers no)
		(fp_rect
			(start -0.3048 0.9906)
			(end 0.3048 -0.1016)
			(stroke
				(width 0)
				(type default)
			)
			(fill no)
			(layer "F.CrtYd")
		)
		(fp_line
			(start -0.3048 -0.1016)
			(end -0.3048 0.9906)
			(stroke
				(width 0.1)
				(type default)
			)
			(layer "F.Fab")
		)
		(fp_line
			(start -0.3048 0.9906)
			(end 0.3048 0.9906)
			(stroke
				(width 0.1)
				(type default)
			)
			(layer "F.Fab")
		)
		(fp_line
			(start 0.3048 -0.1016)
			(end -0.3048 -0.1016)
			(stroke
				(width 0.1)
				(type default)
			)
			(layer "F.Fab")
		)
		(fp_line
			(start 0.3048 0.9906)
			(end 0.3048 -0.1016)
			(stroke
				(width 0.1)
				(type default)
			)
			(layer "F.Fab")
		)
		(pad "1" smd rect
			(at 0 0)
			(size 0.508 0.508)
			(layers "F.Cu" "F.Mask" "F.Paste")
			(net "P3E_CPU0_PE2_SS_TXN<7>")
		)
		(pad "2" smd rect
			(at 0 0.889)
			(size 0.508 0.508)
			(layers "F.Cu" "F.Mask" "F.Paste")
			(net "P3E_CPU0_PE2_SS_C_TXN<7>")
		)
		(zone
			(layer "F.Cu")
			(hatch none 0.5)
			(connect_pads
				(clearance 0)
			)
			(min_thickness 0.25)
			(keepout
				(tracks allowed)
				(vias not_allowed)
				(pads allowed)
				(copperpour not_allowed)
				(footprints allowed)
			)
			(placement
				(enabled no)
				(sheetname "")
			)
			(fill
				(thermal_gap 0.5)
				(thermal_bridge_width 0.5)
				(island_removal_mode 0)
			)
			(polygon
				(pts
					(xy 393.889992 -10.282936) (xy 394.397992 -10.282936) (xy 394.397992 -10.663936) (xy 393.889992 -10.663936)
				)
			)
		)
		(zone
			(layer "F.Cu")
			(hatch none 0.5)
			(connect_pads
				(clearance 0)
			)
			(min_thickness 0.25)
			(keepout
				(tracks not_allowed)
				(vias allowed)
				(pads allowed)
				(copperpour not_allowed)
				(footprints allowed)
			)
			(placement
				(enabled no)
				(sheetname "")
			)
			(fill
				(thermal_gap 0.5)
				(thermal_bridge_width 0.5)
				(island_removal_mode 0)
			)
			(polygon
				(pts
					(xy 393.889992 -10.282936) (xy 394.397992 -10.282936) (xy 394.397992 -10.663936) (xy 393.889992 -10.663936)
				)
			)
		)
	)
)
